(kicad_pcb
	(version 20241229)
	(generator "pcbnew")
	(generator_version "9.0")
	(general
		(thickness 1.711)
		(legacy_teardrops no)
	)
	(paper "A4")
	(title_block
		(title "Antmicro Baseboard for Jetson AGX Thor")
		(date "2026-02-18")
		(rev "1.1.0")
		(company "Antmicro Ltd")
		(comment 1 "www.antmicro.com")
		(comment 9 "footprints 1094-1098 of 1170")
	)
	(layers
		(0 "F.Cu" signal)
		(4 "In1.Cu" signal)
		(6 "In2.Cu" signal)
		(8 "In3.Cu" signal)
		(10 "In4.Cu" jumper)
		(12 "In5.Cu" signal)
		(14 "In6.Cu" signal)
		(16 "In7.Cu" signal)
		(18 "In8.Cu" signal)
		(2 "B.Cu" signal)
		(9 "F.Adhes" user "F.Adhesive")
		(11 "B.Adhes" user "B.Adhesive")
		(13 "F.Paste" user)
		(15 "B.Paste" user)
		(5 "F.SilkS" user "F.Silkscreen")
		(7 "B.SilkS" user "B.Silkscreen")
		(1 "F.Mask" user)
		(3 "B.Mask" user)
		(17 "Dwgs.User" user "User.Drawings")
		(19 "Cmts.User" user "User.Comments")
		(21 "Eco1.User" user "User.Eco1")
		(23 "Eco2.User" user "User.Eco2")
		(25 "Edge.Cuts" user)
		(27 "Margin" user)
		(31 "F.CrtYd" user "F.Courtyard")
		(29 "B.CrtYd" user "B.Courtyard")
		(35 "F.Fab" user)
		(33 "B.Fab" user)
	)
	(footprint "antmicro-footprints:TP_SMD_0.75mm"
		(layer "B.Cu")
		(at 86.6 59.4 180)
		(property "Reference" "TP121"
			(at -3.85 -0.46 0)
			(layer "B.SilkS")
			(effects
				(font
					(size 0.7 0.7)
					(thickness 0.15)
				)
				(justify left bottom mirror)
			)
		)
		(property "Value" "TP_0.75mm_SMD"
			(at 0 -1.2 0)
			(layer "B.Fab")
			(effects
				(font
					(size 0.7 0.7)
					(thickness 0.15)
				)
				(justify left bottom mirror)
			)
		)
		(property "Description" "SMT test point"
			(at 0 0 0)
			(layer "B.Fab")
			(hide yes)
			(effects
				(font
					(size 1.27 1.27)
					(thickness 0.15)
				)
				(justify mirror)
			)
		)
		(property "MPN" ""
			(at 0 0 0)
			(unlocked yes)
			(layer "B.Fab")
			(hide yes)
			(effects
				(font
					(size 1 1)
					(thickness 0.15)
				)
				(justify mirror)
			)
		)
		(property "Manufacturer" ""
			(at 0 0 0)
			(unlocked yes)
			(layer "B.Fab")
			(hide yes)
			(effects
				(font
					(size 1 1)
					(thickness 0.15)
				)
				(justify mirror)
			)
		)
		(property "Author" "Antmicro"
			(at 0 0 0)
			(unlocked yes)
			(layer "B.Fab")
			(hide yes)
			(effects
				(font
					(size 1 1)
					(thickness 0.15)
				)
				(justify mirror)
			)
		)
		(property "License" "Apache-2.0"
			(at 0 0 0)
			(unlocked yes)
			(layer "B.Fab")
			(hide yes)
			(effects
				(font
					(size 1 1)
					(thickness 0.15)
				)
				(justify mirror)
			)
		)
		(sheetname "/SoM_Power/")
		(sheetfile "som_power.kicad_sch")
		(attr exclude_from_pos_files exclude_from_bom)
		(fp_circle
			(center 0 0)
			(end 0.475 0)
			(stroke
				(width 0.05)
				(type default)
			)
			(fill no)
			(layer "B.CrtYd")
		)
		(fp_text user "License: Apache-2.0"
			(at -0.4 -5.101 0)
			(layer "B.Fab")
			(effects
				(font
					(size 0.7 0.7)
					(thickness 0.15)
				)
				(justify left bottom mirror)
			)
		)
		(fp_text user "${REFERENCE}"
			(at -0.4 -2.7 0)
			(layer "B.Fab")
			(effects
				(font
					(size 0.7 0.7)
					(thickness 0.15)
				)
				(justify left bottom mirror)
			)
		)
		(fp_text user "Author: Antmicro"
			(at -0.4 -3.901 0)
			(layer "B.Fab")
			(effects
				(font
					(size 0.7 0.7)
					(thickness 0.15)
				)
				(justify left bottom mirror)
			)
		)
		(pad "1" smd circle
			(at 0 0 180)
			(size 0.75 0.75)
			(layers "B.Cu" "B.Mask")
			(net 85 "/SoM_Power/~{SOM_POWER_BTN}")
			(pinfunction "1")
			(pintype "passive")
		)
	)
	(footprint "antmicro-footprints:R_0402_1005Metric"
		(layer "B.Cu")
		(at 62.1 70.4 90)
		(descr "Resistor SMD 0402")
		(tags "resistor SMD 0402")
		(property "Reference" "R181"
			(at -2.2 3.7 90)
			(layer "B.SilkS")
			(effects
				(font
					(size 0.7 0.7)
					(thickness 0.15)
				)
				(justify right top mirror)
			)
		)
		(property "Value" "R_0R_0402"
			(at -1.011843 -1.772047 90)
			(layer "B.Fab")
			(effects
				(font
					(size 0.7 0.7)
					(thickness 0.15)
				)
				(justify right top mirror)
			)
		)
		(property "Datasheet" "https://industrial.panasonic.com/cdbs/www-data/pdf/RDA0000/AOA0000C301.pdf"
			(at 0 0 90)
			(layer "B.Fab")
			(hide yes)
			(effects
				(font
					(size 1.27 1.27)
					(thickness 0.15)
				)
				(justify mirror)
			)
		)
		(property "Description" "SMD Chip Resistor, Jumper, 0 ohm, 100 mW, 0402 [1005 Metric], Thick Film, General Purpose"
			(at 0 0 90)
			(layer "B.Fab")
			(hide yes)
			(effects
				(font
					(size 1.27 1.27)
					(thickness 0.15)
				)
				(justify mirror)
			)
		)
		(property "MPN" "ERJ2GE0R00X"
			(at 0 0 270)
			(unlocked yes)
			(layer "B.Fab")
			(hide yes)
			(effects
				(font
					(size 1 1)
					(thickness 0.15)
				)
				(justify mirror)
			)
		)
		(property "Manufacturer" "Panasonic"
			(at 0 0 270)
			(unlocked yes)
			(layer "B.Fab")
			(hide yes)
			(effects
				(font
					(size 1 1)
					(thickness 0.15)
				)
				(justify mirror)
			)
		)
		(property "License" "Apache-2.0"
			(at 0 0 270)
			(unlocked yes)
			(layer "B.Fab")
			(hide yes)
			(effects
				(font
					(size 1 1)
					(thickness 0.15)
				)
				(justify mirror)
			)
		)
		(property "Author" "Antmicro"
			(at 0 0 270)
			(unlocked yes)
			(layer "B.Fab")
			(hide yes)
			(effects
				(font
					(size 1 1)
					(thickness 0.15)
				)
				(justify mirror)
			)
		)
		(property "Val" "0R"
			(at 0 0 270)
			(unlocked yes)
			(layer "B.Fab")
			(hide yes)
			(effects
				(font
					(size 1 1)
					(thickness 0.15)
				)
				(justify mirror)
			)
		)
		(property "Tolerance" "~"
			(at 0 0 270)
			(unlocked yes)
			(layer "B.Fab")
			(hide yes)
			(effects
				(font
					(size 1 1)
					(thickness 0.15)
				)
				(justify mirror)
			)
		)
		(property "Current" "1A"
			(at 0 0 270)
			(unlocked yes)
			(layer "B.Fab")
			(hide yes)
			(effects
				(font
					(size 1 1)
					(thickness 0.15)
				)
				(justify mirror)
			)
		)
		(sheetname "/CSI/")
		(sheetfile "csi.kicad_sch")
		(attr smd)
		(fp_rect
			(start -0.925 0.47)
			(end 0.925 -0.47)
			(stroke
				(width 0.05)
				(type default)
			)
			(fill no)
			(layer "B.CrtYd")
		)
		(fp_rect
			(start -0.5 0.25)
			(end 0.5 -0.25)
			(stroke
				(width 0.15)
				(type solid)
			)
			(fill no)
			(layer "B.Fab")
		)
		(fp_text user "Author: Antmicro"
			(at -0.95 -4.169 90)
			(layer "B.Fab")
			(effects
				(font
					(size 0.7 0.7)
					(thickness 0.15)
				)
				(justify right top mirror)
			)
		)
		(fp_text user "${REFERENCE}"
			(at -0.95 -3.168 90)
			(layer "B.Fab")
			(effects
				(font
					(size 0.7 0.7)
					(thickness 0.15)
				)
				(justify right top mirror)
			)
		)
		(fp_text user "License: Apache-2.0"
			(at -0.95 -5.169 90)
			(layer "B.Fab")
			(effects
				(font
					(size 0.7 0.7)
					(thickness 0.15)
				)
				(justify right top mirror)
			)
		)
		(pad "1" smd roundrect
			(at -0.48 0 90)
			(size 0.59 0.64)
			(layers "B.Cu" "B.Mask" "B.Paste")
			(roundrect_rratio 0.25)
			(net 1374 "Net-(J11-Pad39)")
			(pintype "passive")
		)
		(pad "2" smd roundrect
			(at 0.48 0 90)
			(size 0.59 0.64)
			(layers "B.Cu" "B.Mask" "B.Paste")
			(roundrect_rratio 0.25)
			(net 987 "/CSI/SDA_CAM0")
			(pintype "passive")
		)
	)
	(footprint "antmicro-footprints:QFN-2L_1.6x1x0.55mm"
		(layer "B.Cu")
		(at 235.106 74.6)
		(property "Reference" "D23"
			(at 3.594 0.4 0)
			(layer "B.SilkS")
			(effects
				(font
					(size 0.7 0.7)
					(thickness 0.15)
				)
				(justify left bottom mirror)
			)
		)
		(property "Value" "ESDA25P35-1U1M"
			(at 0 -1.7 180)
			(layer "B.Fab")
			(effects
				(font
					(size 0.7 0.7)
					(thickness 0.15)
				)
				(justify left bottom mirror)
			)
		)
		(property "Datasheet" "https://www.st.com/resource/en/datasheet/esda25p35-1u1m.pdf"
			(at 0 0 180)
			(layer "B.Fab")
			(hide yes)
			(effects
				(font
					(size 1.27 1.27)
					(thickness 0.15)
				)
				(justify mirror)
			)
		)
		(property "Description" "Unidirectional TVS, 30 kV, QFN-2L, 22 V, 195 pF"
			(at 0 0 180)
			(layer "B.Fab")
			(hide yes)
			(effects
				(font
					(size 1.27 1.27)
					(thickness 0.15)
				)
				(justify mirror)
			)
		)
		(property "Manufacturer" "STMicroelectronics"
			(at 0 0 0)
			(unlocked yes)
			(layer "B.Fab")
			(hide yes)
			(effects
				(font
					(size 1 1)
					(thickness 0.15)
				)
				(justify mirror)
			)
		)
		(property "MPN" "ESDA25P35-1U1M"
			(at 0 0 0)
			(unlocked yes)
			(layer "B.Fab")
			(hide yes)
			(effects
				(font
					(size 1 1)
					(thickness 0.15)
				)
				(justify mirror)
			)
		)
		(property "Author" "Antmicro"
			(at 0 0 0)
			(unlocked yes)
			(layer "B.Fab")
			(hide yes)
			(effects
				(font
					(size 1 1)
					(thickness 0.15)
				)
				(justify mirror)
			)
		)
		(property "License" "Apache-2.0"
			(at 0 0 0)
			(unlocked yes)
			(layer "B.Fab")
			(hide yes)
			(effects
				(font
					(size 1 1)
					(thickness 0.15)
				)
				(justify mirror)
			)
		)
		(sheetname "/USB Debug, PD/")
		(sheetfile "usb_debug_pd.kicad_sch")
		(attr smd)
		(fp_line
			(start -1.2 0.4)
			(end -1.2 -0.4)
			(stroke
				(width 0.15)
				(type solid)
			)
			(layer "B.SilkS")
		)
		(fp_line
			(start 0.23 -0.45)
			(end -0.23 -0.45)
			(stroke
				(width 0.15)
				(type solid)
			)
			(layer "B.SilkS")
		)
		(fp_line
			(start 0.23 0.45)
			(end -0.23 0.45)
			(stroke
				(width 0.15)
				(type solid)
			)
			(layer "B.SilkS")
		)
		(fp_rect
			(start 1.25 -0.65)
			(end -1.25 0.65)
			(stroke
				(width 0.05)
				(type solid)
			)
			(fill no)
			(layer "B.CrtYd")
		)
		(fp_line
			(start -0.199 -0.2)
			(end -0.199 -0.1)
			(stroke
				(width 0.15)
				(type solid)
			)
			(layer "B.Fab")
		)
		(fp_line
			(start -0.199 0)
			(end -0.597 0)
			(stroke
				(width 0.15)
				(type solid)
			)
			(layer "B.Fab")
		)
		(fp_line
			(start -0.199 0.202)
			(end -0.199 -0.1)
			(stroke
				(width 0.15)
				(type solid)
			)
			(layer "B.Fab")
		)
		(fp_line
			(start -0.101 0)
			(end 0.201 -0.2)
			(stroke
				(width 0.15)
				(type solid)
			)
			(layer "B.Fab")
		)
		(fp_line
			(start 0.201 -0.2)
			(end 0.201 0)
			(stroke
				(width 0.15)
				(type solid)
			)
			(layer "B.Fab")
		)
		(fp_line
			(start 0.201 0)
			(end 0.201 0.202)
			(stroke
				(width 0.15)
				(type solid)
			)
			(layer "B.Fab")
		)
		(fp_line
			(start 0.201 0.202)
			(end -0.101 0)
			(stroke
				(width 0.15)
				(type solid)
			)
			(layer "B.Fab")
		)
		(fp_line
			(start 0.599 0)
			(end 0.201 0)
			(stroke
				(width 0.15)
				(type solid)
			)
			(layer "B.Fab")
		)
		(fp_rect
			(start 0.848 -0.4)
			(end -0.85 0.402)
			(stroke
				(width 0.15)
				(type solid)
			)
			(fill no)
			(layer "B.Fab")
		)
		(fp_text user "License: Apache-2.0"
			(at -1.31 -5.769 180)
			(layer "B.Fab")
			(effects
				(font
					(size 0.7 0.7)
					(thickness 0.15)
				)
				(justify left bottom mirror)
			)
		)
		(fp_text user "Author: Antmicro"
			(at -1.31 -4.769 180)
			(layer "B.Fab")
			(effects
				(font
					(size 0.7 0.7)
					(thickness 0.15)
				)
				(justify left bottom mirror)
			)
		)
		(fp_text user "${REFERENCE}"
			(at -1.31 -3.769 180)
			(layer "B.Fab")
			(effects
				(font
					(size 0.7 0.7)
					(thickness 0.15)
				)
				(justify left bottom mirror)
			)
		)
		(pad "1" smd roundrect
			(at -0.7 0 180)
			(size 0.8 1)
			(layers "B.Cu" "B.Mask" "B.Paste")
			(roundrect_rratio 0.2)
			(net 176 "/USB Debug, PD/USBC0_VBUS")
			(pinfunction "C")
			(pintype "passive")
		)
		(pad "2" smd roundrect
			(at 0.7 0 180)
			(size 0.8 1)
			(layers "B.Cu" "B.Mask" "B.Paste")
			(roundrect_rratio 0.2)
			(net 1 "GND")
			(pinfunction "A")
			(pintype "passive")
		)
	)
	(footprint "antmicro-footprints:C_0402_1005Metric"
		(layer "B.Cu")
		(at 100.5 57.5 90)
		(descr "Capacitor SMD 0402")
		(tags "capacitor SMD 0402")
		(property "Reference" "C225"
			(at -1.6 0.45 90)
			(layer "B.SilkS")
			(effects
				(font
					(size 0.7 0.7)
					(thickness 0.15)
				)
				(justify right top mirror)
			)
		)
		(property "Value" "C_100n_0402"
			(at -1.022927 -2.155213 90)
			(layer "B.Fab")
			(effects
				(font
					(size 0.7 0.7)
					(thickness 0.15)
				)
				(justify right top mirror)
			)
		)
		(property "Datasheet" "https://www.murata.com/products/productdetail?partno=GRM155R61H104KE14%23"
			(at 0 0 90)
			(layer "B.Fab")
			(hide yes)
			(effects
				(font
					(size 1.27 1.27)
					(thickness 0.15)
				)
				(justify mirror)
			)
		)
		(property "Description" "SMD Multilayer Ceramic Capacitor, 0.1 µF, 50 V, 0402 [1005 Metric], ± 10%, X5R, GRM Series"
			(at 0 0 90)
			(layer "B.Fab")
			(hide yes)
			(effects
				(font
					(size 1.27 1.27)
					(thickness 0.15)
				)
				(justify mirror)
			)
		)
		(property "MPN" "GRM155R61H104KE14D"
			(at 0 0 270)
			(unlocked yes)
			(layer "B.Fab")
			(hide yes)
			(effects
				(font
					(size 1 1)
					(thickness 0.15)
				)
				(justify mirror)
			)
		)
		(property "Manufacturer" "Murata"
			(at 0 0 270)
			(unlocked yes)
			(layer "B.Fab")
			(hide yes)
			(effects
				(font
					(size 1 1)
					(thickness 0.15)
				)
				(justify mirror)
			)
		)
		(property "License" "Apache-2.0"
			(at 0 0 270)
			(unlocked yes)
			(layer "B.Fab")
			(hide yes)
			(effects
				(font
					(size 1 1)
					(thickness 0.15)
				)
				(justify mirror)
			)
		)
		(property "Author" "Antmicro"
			(at 0 0 270)
			(unlocked yes)
			(layer "B.Fab")
			(hide yes)
			(effects
				(font
					(size 1 1)
					(thickness 0.15)
				)
				(justify mirror)
			)
		)
		(property "Val" "100n"
			(at 0 0 270)
			(unlocked yes)
			(layer "B.Fab")
			(hide yes)
			(effects
				(font
					(size 1 1)
					(thickness 0.15)
				)
				(justify mirror)
			)
		)
		(property "Voltage" "50V"
			(at 0 0 270)
			(unlocked yes)
			(layer "B.Fab")
			(hide yes)
			(effects
				(font
					(size 1 1)
					(thickness 0.15)
				)
				(justify mirror)
			)
		)
		(property "Dielectric" "X5R"
			(at 0 0 270)
			(unlocked yes)
			(layer "B.Fab")
			(hide yes)
			(effects
				(font
					(size 1 1)
					(thickness 0.15)
				)
				(justify mirror)
			)
		)
		(property "Public" "False"
			(at 0 0 270)
			(unlocked yes)
			(layer "B.Fab")
			(hide yes)
			(effects
				(font
					(size 1 1)
					(thickness 0.15)
				)
				(justify mirror)
			)
		)
		(sheetname "/SoM_Power/")
		(sheetfile "som_power.kicad_sch")
		(attr smd)
		(fp_poly
			(pts
				(xy -0.925 0.47) (xy 0.925 0.47) (xy 0.925 -0.47) (xy -0.925 -0.47)
			)
			(stroke
				(width 0.05)
				(type default)
			)
			(fill no)
			(layer "B.CrtYd")
		)
		(fp_line
			(start 0.504 -0.248)
			(end -0.494 -0.248)
			(stroke
				(width 0.15)
				(type solid)
			)
			(layer "B.Fab")
		)
		(fp_line
			(start -0.494 -0.248)
			(end -0.494 0.25)
			(stroke
				(width 0.15)
				(type solid)
			)
			(layer "B.Fab")
		)
		(fp_line
			(start 0.504 0.25)
			(end 0.504 -0.248)
			(stroke
				(width 0.15)
				(type solid)
			)
			(layer "B.Fab")
		)
		(fp_line
			(start -0.494 0.25)
			(end 0.504 0.25)
			(stroke
				(width 0.15)
				(type solid)
			)
			(layer "B.Fab")
		)
		(fp_text user "Author: Antmicro"
			(at -0.939 -3.399 90)
			(layer "B.Fab")
			(effects
				(font
					(size 0.7 0.7)
					(thickness 0.15)
				)
				(justify right top mirror)
			)
		)
		(fp_text user "${REFERENCE}"
			(at -0.939 -4.599 90)
			(layer "B.Fab")
			(effects
				(font
					(size 0.7 0.7)
					(thickness 0.15)
				)
				(justify right top mirror)
			)
		)
		(fp_text user "License: Apache-2.0"
			(at -0.939 -5.799 90)
			(layer "B.Fab")
			(effects
				(font
					(size 0.7 0.7)
					(thickness 0.15)
				)
				(justify right top mirror)
			)
		)
		(pad "1" smd roundrect
			(at -0.48 0 90)
			(size 0.59 0.64)
			(layers "B.Cu" "B.Mask" "B.Paste")
			(roundrect_rratio 0.25)
			(net 1 "GND")
			(pintype "passive")
		)
		(pad "2" smd roundrect
			(at 0.48 0 90)
			(size 0.59 0.64)
			(layers "B.Cu" "B.Mask" "B.Paste")
			(roundrect_rratio 0.25)
			(net 4 "+3V3_AON")
			(pintype "passive")
		)
	)
	(footprint "antmicro-footprints:TP_SMD_0.75mm"
		(layer "B.Cu")
		(at 147.75 144.75 -90)
		(property "Reference" "TP78"
			(at -3.35 -0.45 90)
			(layer "B.SilkS")
			(effects
				(font
					(size 0.7 0.7)
					(thickness 0.15)
				)
				(justify left bottom mirror)
			)
		)
		(property "Value" "TP_0.75mm_SMD"
			(at 0 -1.2 90)
			(layer "B.Fab")
			(effects
				(font
					(size 0.7 0.7)
					(thickness 0.15)
				)
				(justify left bottom mirror)
			)
		)
		(property "Description" "SMT test point"
			(at 0 0 90)
			(layer "B.Fab")
			(hide yes)
			(effects
				(font
					(size 1.27 1.27)
					(thickness 0.15)
				)
				(justify mirror)
			)
		)
		(property "MPN" ""
			(at 0 0 90)
			(unlocked yes)
			(layer "B.Fab")
			(hide yes)
			(effects
				(font
					(size 1 1)
					(thickness 0.15)
				)
				(justify mirror)
			)
		)
		(property "Manufacturer" ""
			(at 0 0 90)
			(unlocked yes)
			(layer "B.Fab")
			(hide yes)
			(effects
				(font
					(size 1 1)
					(thickness 0.15)
				)
				(justify mirror)
			)
		)
		(property "Author" "Antmicro"
			(at 0 0 90)
			(unlocked yes)
			(layer "B.Fab")
			(hide yes)
			(effects
				(font
					(size 1 1)
					(thickness 0.15)
				)
				(justify mirror)
			)
		)
		(property "License" "Apache-2.0"
			(at 0 0 90)
			(unlocked yes)
			(layer "B.Fab")
			(hide yes)
			(effects
				(font
					(size 1 1)
					(thickness 0.15)
				)
				(justify mirror)
			)
		)
		(sheetname "/SoM_Power/")
		(sheetfile "som_power.kicad_sch")
		(attr exclude_from_pos_files exclude_from_bom)
		(fp_circle
			(center 0 0)
			(end 0.475 0)
			(stroke
				(width 0.05)
				(type default)
			)
			(fill no)
			(layer "B.CrtYd")
		)
		(fp_text user "License: Apache-2.0"
			(at -0.4 -5.101 90)
			(layer "B.Fab")
			(effects
				(font
					(size 0.7 0.7)
					(thickness 0.15)
				)
				(justify left bottom mirror)
			)
		)
		(fp_text user "Author: Antmicro"
			(at -0.4 -3.901 90)
			(layer "B.Fab")
			(effects
				(font
					(size 0.7 0.7)
					(thickness 0.15)
				)
				(justify left bottom mirror)
			)
		)
		(fp_text user "${REFERENCE}"
			(at -0.4 -2.7 90)
			(layer "B.Fab")
			(effects
				(font
					(size 0.7 0.7)
					(thickness 0.15)
				)
				(justify left bottom mirror)
			)
		)
		(pad "1" smd circle
			(at 0 0 270)
			(size 0.75 0.75)
			(layers "B.Cu" "B.Mask")
			(net 32 "Net-(D1-C)")
			(pinfunction "1")
			(pintype "passive")
		)
	)
)
